# T6G (Grand Teton) — schematic netlist excerpt (pin names and nets, part order shuffled) for the footprints in the layout excerpt that follows; sources: Cadence DE-HDL packaged netlist, KiCad conversion of 04192023_DAF0TMB3IC0_F0TG_MB_C_brd_V02_OCP.brd

J35  SCONN168_ME1016810202011  IO  pkg CON_F168S2H7D_P0-6W2-95_LUH  page 137
  GND_A1  = GND
  GND_A2  = GND
  GND_A3  = GND
  GND_A4  = GND
  GND_A5  = GND
  GND_A6  = GND
  SMCLK  = SMB_OCP_V3_2_3V3AUX_BUF_R_SCL
  SMDAT  = SMB_OCP_V3_2_3V3AUX_BUF_R_SDA
  \smrst#\  = RST_SMB_OCP_V3_2_N
  \prsnta#\  = OCP_V3_2_PRSNTA_R_N
  \perst1#\  = RST_PERST1_OCP_V3_2_N
  \prsntb2#\  = OCP_V3_2_PRSNT2_R_N
  GND_A13  = GND
  REFCLKN1  = CLK_100M_CPU1_CLK03_DN
  REFCLKP1  = CLK_100M_CPU1_CLK03_DP
  GND_A16  = GND
  PERN0  = P5E_CPU1_G1_RX_DN<0>
  PERP0  = P5E_CPU1_G1_RX_DP<0>
  GND_A19  = GND
  PERN1  = P5E_CPU1_G1_RX_DN<1>
  PERP1  = P5E_CPU1_G1_RX_DP<1>
  GND_A22  = GND
  PERN2  = P5E_CPU1_G1_RX_DN<2>
  PERP2  = P5E_CPU1_G1_RX_DP<2>
  GND_A25  = GND
  PERN3  = P5E_CPU1_G1_RX_DN<3>
  PERP3  = P5E_CPU1_G1_RX_DP<3>
  GND_A28  = GND
  GND_A29  = GND
  PERN4  = P5E_CPU1_G1_RX_DN<4>
  PERP4  = P5E_CPU1_G1_RX_DP<4>
  GND_A32  = GND
  PERN5  = P5E_CPU1_G1_RX_DN<5>
  PERP5  = P5E_CPU1_G1_RX_DP<5>
  GND_A35  = GND
  PERN6  = P5E_CPU1_G1_RX_DN<6>
  PERP6  = P5E_CPU1_G1_RX_DP<6>
  GND_A38  = GND
  PERN7  = P5E_CPU1_G1_RX_DN<7>
  PERP7  = P5E_CPU1_G1_RX_DP<7>
  GND_A41  = GND
  \prsntb1#\  = OCP_V3_2_PRSNT1_R_N
  GND_A43  = GND
  PERN8  = P5E_CPU1_G1_RX_DN<8>
  PERP8  = P5E_CPU1_G1_RX_DP<8>
  GND_A46  = GND
  PERN9  = P5E_CPU1_G1_RX_DN<9>
  PERP9  = P5E_CPU1_G1_RX_DP<9>
  GND_A49  = GND
  PERN10  = P5E_CPU1_G1_RX_DN<10>
  PERP10  = P5E_CPU1_G1_RX_DP<10>
  GND_A52  = GND
  PERN11  = P5E_CPU1_G1_RX_DN<11>
  PERP11  = P5E_CPU1_G1_RX_DP<11>
  GND_A55  = GND
  PERN12  = P5E_CPU1_G1_RX_DN<12>
  PERP12  = P5E_CPU1_G1_RX_DP<12>
  GND_A58  = GND
  PERN13  = P5E_CPU1_G1_RX_DN<13>
  PERP13  = P5E_CPU1_G1_RX_DP<13>
  GND_A61  = GND
  PERN14  = P5E_CPU1_G1_RX_DN<14>
  PERP14  = P5E_CPU1_G1_RX_DP<14>
  GND_A64  = GND
  PERN15  = P5E_CPU1_G1_RX_DN<15>
  PERP15  = P5E_CPU1_G1_RX_DP<15>
  GND_A67  = GND
  USB_DATN  = USB2_P10_DN
  USB_DATP  = USB2_P10_DP
  \pwrbrk0#\  = OCP_V3_2_PWRBRK_N
  \+12v_edge_b1\  = P12V_OCP_V3_2_R
  \+12v_edge_b2\  = P12V_OCP_V3_2_R
  \+12v_edge_b3\  = P12V_OCP_V3_2_R
  \+12v_edge_b4\  = P12V_OCP_V3_2_R
  \+12v_edge_b5\  = P12V_OCP_V3_2_R
  \+12v_edge_b6\  = P12V_OCP_V3_2_R
  \bif0#\  = OCP_V3_2_BIF0_R_N
  \bif1#\  = OCP_V3_2_BIF1_R_N
  \bif2#\  = OCP_V3_2_BIF2_R_N
  \perst0#\  = RST_PERST0_OCP_V3_2_N
  \+3.3v_edge\  = P3V3_OCP_V3_2
  AUX_PWR_EN  = OCP_V3_2_AUX_PWR_EN_R
  GND_B13  = GND
  REFCLKN0  = CLK_100M_CPU1_CLK02_DN
  REFCLKP0  = CLK_100M_CPU1_CLK02_DP
  GND_B16  = GND
  PETN0  = P5E_CPU1_G1_TX_C_DP<0>
  PETP0  = P5E_CPU1_G1_TX_C_DN<0>
  GND_B19  = GND
  PETN1  = P5E_CPU1_G1_TX_C_DP<1>
  PETP1  = P5E_CPU1_G1_TX_C_DN<1>
  GND_B22  = GND
  PETN2  = P5E_CPU1_G1_TX_C_DP<2>
  PETP2  = P5E_CPU1_G1_TX_C_DN<2>
  GND_B25  = GND
  PETN3  = P5E_CPU1_G1_TX_C_DP<3>
  PETP3  = P5E_CPU1_G1_TX_C_DN<3>
  GND_B28  = GND
  GND_B29  = GND
  PETN4  = P5E_CPU1_G1_TX_C_DP<4>
  PETP4  = P5E_CPU1_G1_TX_C_DN<4>
  GND_B32  = GND
  PETN5  = P5E_CPU1_G1_TX_C_DP<5>
  PETP5  = P5E_CPU1_G1_TX_C_DN<5>
  GND_B35  = GND
  PETN6  = P5E_CPU1_G1_TX_C_DP<6>
  PETP6  = P5E_CPU1_G1_TX_C_DN<6>
  GND_B38  = GND
  PETN7  = P5E_CPU1_G1_TX_C_DP<7>
  PETP7  = P5E_CPU1_G1_TX_C_DN<7>
  GND_B41  = GND
  \prsntb0#\  = OCP_V3_2_PRSNT0_R_N
  GND_B43  = GND
  PETN8  = P5E_CPU1_G1_TX_C_DP<8>
  PETP8  = P5E_CPU1_G1_TX_C_DN<8>
  GND_B46  = GND
  PETN9  = P5E_CPU1_G1_TX_C_DP<9>
  PETP9  = P5E_CPU1_G1_TX_C_DN<9>
  GND_B49  = GND
  PETN10  = P5E_CPU1_G1_TX_C_DP<10>
  PETP10  = P5E_CPU1_G1_TX_C_DN<10>
  GND_B52  = GND
  PETN11  = P5E_CPU1_G1_TX_C_DP<11>
  PETP11  = P5E_CPU1_G1_TX_C_DN<11>
  GND_B55  = GND
  PETN12  = P5E_CPU1_G1_TX_C_DP<12>
  PETP12  = P5E_CPU1_G1_TX_C_DN<12>
  GND_B58  = GND
  PETN13  = P5E_CPU1_G1_TX_C_DP<13>
  PETP13  = P5E_CPU1_G1_TX_C_DN<13>
  GND_B61  = GND
  PETN14  = P5E_CPU1_G1_TX_C_DP<14>
  PETP14  = P5E_CPU1_G1_TX_C_DN<14>
  GND_B64  = GND
  PETN15  = P5E_CPU1_G1_TX_C_DP<15>
  PETP15  = P5E_CPU1_G1_TX_C_DN<15>
  GND_B67  = GND
  RFU1_NC_B68  = TP_OCP_V3_2_B68
  RFU1_NC_B69  = TP_OCP_V3_2_B69
  \prsntb3#\  = OCP_V3_2_PRSNT3_R_N
  G1  = GND
  G2  = GND
  G3  = GND
  G4  = GND
  G5  = GND
  \perst2#\  = RST_PERST2_OCP_V3_2_N
  \perst3#\  = RST_PERST3_OCP_V3_2_N
  \wake#\  = IRQ_LVC3_OCP_V3_2_WAKE_N
  RBT_ARB_IN  = OCP_V3_2_ISO1_RBT_ARB_IN
  RBT_ARB_OUT  = OCP_V3_2_ISO2_RBT_ARB_OUT
  SLOT_ID1  = OCP_V3_2_ID1
  RBT_TX_EN  = NCSI_OCP_V3_2_TX_EN
  RBT_TXD1  = NCSI_OCP_V3_2_TXD1
  RBT_TXD0  = NCSI_OCP_V3_2_TXD0
  GND_OA10  = GND
  REFCLKN3  = CLK_100M_CPU1_CLK05_DN
  REFCLKP3  = CLK_100M_CPU1_CLK05_DP
  GND_OA13  = GND
  RBT_CLK_IN  = CLK_50M_NCSI_OCP_V3_2_ISO
  NIC_PWR_GOOD  = FM_OCP_V3_2_PWR_GOOD
  MAIN_PWR_EN  = OCP_V3_2_MAIN_PWR_EN_R
  \ld#\  = SGPIO_OCP_V3_2_LD_N
  DATA_IN  = SGPIO_OCP_V3_2_DATAIN
  DATA_OUT  = SGPIO_OCP_V3_2_DATAOUT
  CLK  = SGPIO_OCP_V3_2_CLK
  SLOT_ID0  = OCP_V3_2_ID0
  RBT_RXD1  = NCSI_OCP_V3_2_RXD1
  RBT_RXD0  = NCSI_OCP_V3_2_RXD0
  GND_OB10  = GND
  REFCLKN2  = CLK_100M_CPU1_CLK04_DN
  REFCLKP2  = CLK_100M_CPU1_CLK04_DP
  GND_OB13  = GND
  RBT_CRS_DV  = NCSI_OCP_V3_2_CRS_DV

(kicad_pcb
	(version 20260206)
	(generator "pcbnew")
	(generator_version "10.0")
	(general
		(thickness 1.6)
		(legacy_teardrops no)
	)
	(paper "A4")
	(title_block
		(title "04192023_DAF0TMB3IC0_F0TG_MB_C_brd_V02_OCP.brd")
		(comment 1 "Grand Teton / footprint 4922 of 8354 (J35), pads 90-133 of 175")
	)
	(layers
		(0 "F.Cu" signal "TOP")
		(4 "In1.Cu" signal "GND")
		(6 "In2.Cu" signal "IN1")
		(8 "In3.Cu" signal "GND1")
		(10 "In4.Cu" signal "IN2")
		(12 "In5.Cu" signal "GND2")
		(14 "In6.Cu" signal "IN3")
		(16 "In7.Cu" signal "GND3")
		(18 "In8.Cu" signal "VCC")
		(20 "In9.Cu" signal "VCC1")
		(22 "In10.Cu" signal "GND4")
		(24 "In11.Cu" signal "IN4")
		(26 "In12.Cu" signal "GND5")
		(28 "In13.Cu" signal "IN5")
		(30 "In14.Cu" signal "GND6")
		(32 "In15.Cu" signal "IN6")
		(34 "In16.Cu" signal "GND7")
		(2 "B.Cu" signal "BOTTOM")
		(9 "F.Adhes" user "F.Adhesive")
		(11 "B.Adhes" user "B.Adhesive")
		(13 "F.Paste" user "Package Geometry/Pastemask Top")
		(15 "B.Paste" user "Package Geometry/Pastemask Bottom")
		(5 "F.SilkS" user "Ref Des/Silkscreen Top")
		(7 "B.SilkS" user "Ref Des/Silkscreen Bottom")
		(1 "F.Mask" user "Board Geometry/Soldermask Top")
		(3 "B.Mask" user "Board Geometry/Soldermask Bottom")
		(17 "Dwgs.User" user "User.Drawings")
		(19 "Cmts.User" user "User.Comments")
		(21 "Eco1.User" user "User.Eco1")
		(23 "Eco2.User" user "User.Eco2")
		(25 "Edge.Cuts" user "Board Geometry/Outline")
		(27 "Margin" user)
		(31 "F.CrtYd" user "Package Geometry/Place Bound Top")
		(29 "B.CrtYd" user "Package Geometry/Place Bound Bottom")
		(35 "F.Fab" user "Ref Des/Assembly Top")
		(33 "B.Fab" user "Ref Des/Assembly Bottom")
	)
	(footprint ""
		(layer "F.Cu")
		(at 47.401988 -5.569966 -90)
		(property "Reference" "J35"
			(at -8.0772 -20.659598 0)
			(unlocked yes)
			(layer "F.SilkS")
			(effects
				(font
					(size 0.7874 0.5842)
					(thickness 0.1524)
				)
				(justify left)
			)
		)
		(property "Value" ""
			(at 0 0 270)
			(layer "F.Fab")
			(effects
				(font
					(size 1.27 1.27)
				)
			)
		)
		(duplicate_pad_numbers_are_jumpers no)
		(pad "B18" smd rect
			(at -5.700014 -8.264906 180)
			(size 0.381 1.4478)
			(layers "F.Cu" "F.Mask" "F.Paste")
			(net "P5E_CPU1_G1_TX_C_DN<0>")
		)
		(pad "B19" smd rect
			(at -5.700014 -7.664958 180)
			(size 0.381 1.4478)
			(layers "F.Cu" "F.Mask" "F.Paste")
			(net "GND")
		)
		(pad "B20" smd rect
			(at -5.700014 -7.06501 180)
			(size 0.381 1.4478)
			(layers "F.Cu" "F.Mask" "F.Paste")
			(net "P5E_CPU1_G1_TX_C_DP<1>")
		)
		(pad "B21" smd rect
			(at -5.700014 -6.465062 180)
			(size 0.381 1.4478)
			(layers "F.Cu" "F.Mask" "F.Paste")
			(net "P5E_CPU1_G1_TX_C_DN<1>")
		)
		(pad "B22" smd rect
			(at -5.700014 -5.865114 180)
			(size 0.381 1.4478)
			(layers "F.Cu" "F.Mask" "F.Paste")
			(net "GND")
		)
		(pad "B23" smd rect
			(at -5.700014 -5.264912 180)
			(size 0.381 1.4478)
			(layers "F.Cu" "F.Mask" "F.Paste")
			(net "P5E_CPU1_G1_TX_C_DP<2>")
		)
		(pad "B24" smd rect
			(at -5.700014 -4.664964 180)
			(size 0.381 1.4478)
			(layers "F.Cu" "F.Mask" "F.Paste")
			(net "P5E_CPU1_G1_TX_C_DN<2>")
		)
		(pad "B25" smd rect
			(at -5.700014 -4.065016 180)
			(size 0.381 1.4478)
			(layers "F.Cu" "F.Mask" "F.Paste")
			(net "GND")
		)
		(pad "B26" smd rect
			(at -5.700014 -3.465068 180)
			(size 0.381 1.4478)
			(layers "F.Cu" "F.Mask" "F.Paste")
			(net "P5E_CPU1_G1_TX_C_DP<3>")
		)
		(pad "B27" smd rect
			(at -5.700014 -2.86512 180)
			(size 0.381 1.4478)
			(layers "F.Cu" "F.Mask" "F.Paste")
			(net "P5E_CPU1_G1_TX_C_DN<3>")
		)
		(pad "B28" smd rect
			(at -5.700014 -2.264918 180)
			(size 0.381 1.4478)
			(layers "F.Cu" "F.Mask" "F.Paste")
			(net "GND")
		)
		(pad "B29" smd rect
			(at -5.700014 1.74498 180)
			(size 0.381 1.4478)
			(layers "F.Cu" "F.Mask" "F.Paste")
			(net "GND")
		)
		(pad "B30" smd rect
			(at -5.700014 2.344928 180)
			(size 0.381 1.4478)
			(layers "F.Cu" "F.Mask" "F.Paste")
			(net "P5E_CPU1_G1_TX_C_DP<4>")
		)
		(pad "B31" smd rect
			(at -5.700014 2.944876 180)
			(size 0.381 1.4478)
			(layers "F.Cu" "F.Mask" "F.Paste")
			(net "P5E_CPU1_G1_TX_C_DN<4>")
		)
		(pad "B32" smd rect
			(at -5.700014 3.545078 180)
			(size 0.381 1.4478)
			(layers "F.Cu" "F.Mask" "F.Paste")
			(net "GND")
		)
		(pad "B33" smd rect
			(at -5.700014 4.145026 180)
			(size 0.381 1.4478)
			(layers "F.Cu" "F.Mask" "F.Paste")
			(net "P5E_CPU1_G1_TX_C_DP<5>")
		)
		(pad "B34" smd rect
			(at -5.700014 4.744974 180)
			(size 0.381 1.4478)
			(layers "F.Cu" "F.Mask" "F.Paste")
			(net "P5E_CPU1_G1_TX_C_DN<5>")
		)
		(pad "B35" smd rect
			(at -5.700014 5.344922 180)
			(size 0.381 1.4478)
			(layers "F.Cu" "F.Mask" "F.Paste")
			(net "GND")
		)
		(pad "B36" smd rect
			(at -5.700014 5.945124 180)
			(size 0.381 1.4478)
			(layers "F.Cu" "F.Mask" "F.Paste")
			(net "P5E_CPU1_G1_TX_C_DP<6>")
		)
		(pad "B37" smd rect
			(at -5.700014 6.545072 180)
			(size 0.381 1.4478)
			(layers "F.Cu" "F.Mask" "F.Paste")
			(net "P5E_CPU1_G1_TX_C_DN<6>")
		)
		(pad "B38" smd rect
			(at -5.700014 7.14502 180)
			(size 0.381 1.4478)
			(layers "F.Cu" "F.Mask" "F.Paste")
			(net "GND")
		)
		(pad "B39" smd rect
			(at -5.700014 7.744968 180)
			(size 0.381 1.4478)
			(layers "F.Cu" "F.Mask" "F.Paste")
			(net "P5E_CPU1_G1_TX_C_DP<7>")
		)
		(pad "B40" smd rect
			(at -5.700014 8.344916 180)
			(size 0.381 1.4478)
			(layers "F.Cu" "F.Mask" "F.Paste")
			(net "P5E_CPU1_G1_TX_C_DN<7>")
		)
		(pad "B41" smd rect
			(at -5.700014 8.945118 180)
			(size 0.381 1.4478)
			(layers "F.Cu" "F.Mask" "F.Paste")
			(net "GND")
		)
		(pad "B42" smd rect
			(at -5.700014 9.545066 180)
			(size 0.381 1.4478)
			(layers "F.Cu" "F.Mask" "F.Paste")
			(net "OCP_V3_2_PRSNT0_R_N")
		)
		(pad "B43" smd rect
			(at -5.700014 14.454886 180)
			(size 0.381 1.4478)
			(layers "F.Cu" "F.Mask" "F.Paste")
			(net "GND")
		)
		(pad "B44" smd rect
			(at -5.700014 15.055088 180)
			(size 0.381 1.4478)
			(layers "F.Cu" "F.Mask" "F.Paste")
			(net "P5E_CPU1_G1_TX_C_DP<8>")
		)
		(pad "B45" smd rect
			(at -5.700014 15.655036 180)
			(size 0.381 1.4478)
			(layers "F.Cu" "F.Mask" "F.Paste")
			(net "P5E_CPU1_G1_TX_C_DN<8>")
		)
		(pad "B46" smd rect
			(at -5.700014 16.254984 180)
			(size 0.381 1.4478)
			(layers "F.Cu" "F.Mask" "F.Paste")
			(net "GND")
		)
		(pad "B47" smd rect
			(at -5.700014 16.854932 180)
			(size 0.381 1.4478)
			(layers "F.Cu" "F.Mask" "F.Paste")
			(net "P5E_CPU1_G1_TX_C_DP<9>")
		)
		(pad "B48" smd rect
			(at -5.700014 17.45488 180)
			(size 0.381 1.4478)
			(layers "F.Cu" "F.Mask" "F.Paste")
			(net "P5E_CPU1_G1_TX_C_DN<9>")
		)
		(pad "B49" smd rect
			(at -5.700014 18.055082 180)
			(size 0.381 1.4478)
			(layers "F.Cu" "F.Mask" "F.Paste")
			(net "GND")
		)
		(pad "B50" smd rect
			(at -5.700014 18.65503 180)
			(size 0.381 1.4478)
			(layers "F.Cu" "F.Mask" "F.Paste")
			(net "P5E_CPU1_G1_TX_C_DP<10>")
		)
		(pad "B51" smd rect
			(at -5.700014 19.254978 180)
			(size 0.381 1.4478)
			(layers "F.Cu" "F.Mask" "F.Paste")
			(net "P5E_CPU1_G1_TX_C_DN<10>")
		)
		(pad "B52" smd rect
			(at -5.700014 19.854926 180)
			(size 0.381 1.4478)
			(layers "F.Cu" "F.Mask" "F.Paste")
			(net "GND")
		)
		(pad "B53" smd rect
			(at -5.700014 20.455128 180)
			(size 0.381 1.4478)
			(layers "F.Cu" "F.Mask" "F.Paste")
			(net "P5E_CPU1_G1_TX_C_DP<11>")
		)
		(pad "B54" smd rect
			(at -5.700014 21.055076 180)
			(size 0.381 1.4478)
			(layers "F.Cu" "F.Mask" "F.Paste")
			(net "P5E_CPU1_G1_TX_C_DN<11>")
		)
		(pad "B55" smd rect
			(at -5.700014 21.655024 180)
			(size 0.381 1.4478)
			(layers "F.Cu" "F.Mask" "F.Paste")
			(net "GND")
		)
		(pad "B56" smd rect
			(at -5.700014 22.254972 180)
			(size 0.381 1.4478)
			(layers "F.Cu" "F.Mask" "F.Paste")
			(net "P5E_CPU1_G1_TX_C_DP<12>")
		)
		(pad "B57" smd rect
			(at -5.700014 22.85492 180)
			(size 0.381 1.4478)
			(layers "F.Cu" "F.Mask" "F.Paste")
			(net "P5E_CPU1_G1_TX_C_DN<12>")
		)
		(pad "B58" smd rect
			(at -5.700014 23.455122 180)
			(size 0.381 1.4478)
			(layers "F.Cu" "F.Mask" "F.Paste")
			(net "GND")
		)
		(pad "B59" smd rect
			(at -5.700014 24.05507 180)
			(size 0.381 1.4478)
			(layers "F.Cu" "F.Mask" "F.Paste")
			(net "P5E_CPU1_G1_TX_C_DP<13>")
		)
		(pad "B60" smd rect
			(at -5.700014 24.655018 180)
			(size 0.381 1.4478)
			(layers "F.Cu" "F.Mask" "F.Paste")
			(net "P5E_CPU1_G1_TX_C_DN<13>")
		)
		(pad "B61" smd rect
			(at -5.700014 25.254966 180)
			(size 0.381 1.4478)
			(layers "F.Cu" "F.Mask" "F.Paste")
			(net "GND")
		)
	)
)
